# Lightning_FCB_Pick & place.xlsx — Sheet1 (pick-and-place)
| 12433-2a.1211/fcb.brd |  |  |  |  |  |  |  |  |
| Date Tue Dec 12 14:22:59 2017 |  |  |  |  |  |  |  |  |
| Total Components:  495 |  |  |  |  |  |  |  |  |
| Component Report |  |  |  |  |  |  |  |  |
| REFDES | COMP_DEVICE_TYPE | COMP_VALUE | COMP_TOL | COMP_PACKAGE | SYM_X | SYM_Y | SYM_ROTATE | SYM_MIRROR |
| C1 | C805H56 | SC10U25V5KX-GP | 78.10622.51L | C805H56 | 1522.65 | 6051.71 | 0 | NO |
| C2 | C402H22 | SCD1U16V2KX-3GP | 78.10421.2FL | C402H22 | 1463.65 | 6095.21 | 0 | NO |
| C3 | C805H56 | SC10U25V5KX-GP | 78.10622.51L | C805H56 | 1701 | 6114 | 180 | NO |
| C4 | C402H22 | SCD1U16V2KX-3GP | 78.10421.2FL | C402H22 | 1646 | 6103 | 180 | NO |
| C5 | C402H22 | SCD1U16V2KX-3GP | 78.10421.2FL | C402H22 | 1035 | 5957 | 0 | NO |
| C6 | C402-TO0D2H26 | SC4D7U6D3V2MX-GP-U | 78.47510.5FL | C402-TO0D2H26 | 1804.65 | 6331.71 | 0 | NO |
| C7 | C402H22 | SC2200P50V2KX-2GP | 78.22224.2FL | C402H22 | 1094 | 5937 | 90 | NO |
| C8 | C402H22 | SC2200P50V2KX-2GP | 78.22224.2FL | C402H22 | 1147 | 6035 | 90 | NO |
| C9 | C603H36 | SC1U16V3KX-5GP | 78.10521.2BL | C603H36 | 656.35 | 6911.06 | 180 | NO |
| C10 | C603H36 | SCD1U50V3KX-GP | 78.10424.2BL | C603H36 | 705.35 | 6911.06 | 180 | NO |
| C11 | C603H36 | SCD1U50V3KX-GP | 78.10424.2BL | C603H36 | 1234.6500000000001 | 6758.94 | 0 | NO |
| C12 | C603H36 | SC1U16V3KX-5GP | 78.10521.2BL | C603H36 | 1290.6500000000001 | 6758.94 | 0 | NO |
| C13 | C603H36 | SC1U16V3KX-5GP | 78.10521.2BL | C603H36 | 1043 | 9908 | 270 | NO |
| C14 | C603H36 | SCD1U50V3KX-GP | 78.10424.2BL | C603H36 | 1043 | 9860 | 270 | NO |
| C15 | C603H36 | SC1U16V3KX-5GP | 78.10521.2BL | C603H36 | 923 | 8756.5400000000009 | 180 | NO |
| C16 | C603H36 | SCD1U50V3KX-GP | 78.10424.2BL | C603H36 | 875 | 8756.5400000000009 | 180 | NO |
| C19 | C603H36 | SC1U16V3KX-5GP | 78.10521.2BL | C603H36 | 1299 | 9897 | 180 | NO |
| C20 | C603H36 | SCD1U50V3KX-GP | 78.10424.2BL | C603H36 | 1308 | 9786 | 0 | NO |
| C23 | C603H36 | SCD1U50V3KX-GP | 78.10424.2BL | C603H36 | 372 | 2943 | 270 | NO |
| C24 | C603H36 | SCD1U50V3KX-GP | 78.10424.2BL | C603H36 | 1141 | 3801 | 270 | NO |
| C25 | C603H36 | SCD1U50V3KX-GP | 78.10424.2BL | C603H36 | 1851 | 16480 | 90 | NO |
| C26 | C603H36 | SC1U25V3KX-1-GP | 78.10522.5BL | C603H36 | 1851 | 16527 | 90 | NO |
| C27 | C402H22 | SCD1U16V2KX-3GP | 78.10421.2FL | C402H22 | 714 | 699.54 | 0 | NO |
| C28 | C402H22 | SCD1U16V2KX-3GP | 78.10421.2FL | C402H22 | 350 | 5831 | 180 | NO |
| C29 | C402H22 | SCD1U16V2KX-3GP | 78.10421.2FL | C402H22 | 718.02 | 547.47 | 0 | NO |
| C30 | C402H22 | SCD1U16V2KX-3GP | 78.10421.2FL | C402H22 | 627 | 5730 | 270 | NO |
| C31 | C603H36 | SCD1U50V3KX-GP | 78.10424.2BL | C603H36 | 522 | 2417 | 0 | NO |
| C32 | C603H36 | SC1U25V3KX-1-GP | 78.10522.5BL | C603H36 | 474.98 | 2416.9899999999998 | 0 | NO |
| C33 | C603H36 | SCD1U50V3KX-GP | 78.10424.2BL | C603H36 | 610 | 6576 | 90 | NO |
| C34 | C603H36 | SC1U25V3KX-1-GP | 78.10522.5BL | C603H36 | 610 | 6623 | 90 | NO |
| C35 | C402H22 | SCD1U16V2KX-3GP | 78.10421.2FL | C402H22 | 581 | 10326 | 180 | NO |
| C36 | C402H22 | SCD1U16V2KX-3GP | 78.10421.2FL | C402H22 | 757 | 7173 | 0 | NO |
| C37 | C402H22 | SCD1U16V2KX-3GP | 78.10421.2FL | C402H22 | 752 | 7397 | 0 | NO |
| C38 | C402H22 | SCD1U16V2KX-3GP | 78.10421.2FL | C402H22 | 538 | 10113 | 0 | NO |
| C39 | C603H36 | SCD1U50V3KX-GP | 78.10424.2BL | C603H36 | 1025 | 10537 | 90 | NO |
| C40 | C603H36 | SC1U25V3KX-1-GP | 78.10522.5BL | C603H36 | 1025 | 10584 | 90 | NO |
| C41 | C603H36 | SCD1U50V3KX-GP | 78.10424.2BL | C603H36 | 1130 | 7641 | 90 | NO |
| C42 | C603H36 | SC1U25V3KX-1-GP | 78.10522.5BL | C603H36 | 1130 | 7691 | 90 | NO |
| C43 | C402H22 | SCD1U16V2KX-3GP | 78.10421.2FL | C402H22 | 694 | 11445 | 270 | NO |
| C44 | C402H22 | SCD1U16V2KX-3GP | 78.10421.2FL | C402H22 | 852 | 11430 | 270 | NO |
| C45 | C402H22 | SCD1U16V2KX-3GP | 78.10421.2FL | C402H22 | 285 | 17878 | 270 | NO |
| C46 | C402H22 | SCD1U16V2KX-3GP | 78.10421.2FL | C402H22 | 500 | 17603 | 90 | NO |
| C47 | C603H36 | SCD1U50V3KX-GP | 78.10424.2BL | C603H36 | 1490.02 | 11141.47 | 0 | NO |
| C48 | C603H36 | SC1U25V3KX-1-GP | 78.10522.5BL | C603H36 | 1443 | 11141 | 0 | NO |
| C49 | C603H36 | SCD1U50V3KX-GP | 78.10424.2BL | C603H36 | 1446 | 18837 | 90 | NO |
| C50 | C603H36 | SC1U25V3KX-1-GP | 78.10522.5BL | C603H36 | 1446.47 | 18786.98 | 90 | NO |
| C51 | C402H22 | SCD1U10V2KX-4-LL-GP | 78.10423.5FLLL | C402H22 | 1315 | 14320 | 270 | NO |
| C52 | C603H36 | SCD1U50V3KX-GP | 78.10424.2BL | C603H36 | 289 | 6881 | 180 | NO |
| C53 | C603H36 | SC1U16V3KX-5GP | 78.10521.2BL | C603H36 | 241 | 6881 | 180 | NO |
| C54 | C603H36 | SCD1U50V3KX-GP | 78.10424.2BL | C603H36 | 672 | 7082 | 180 | NO |
| C55 | C603H36 | SC1U16V3KX-5GP | 78.10521.2BL | C603H36 | 722 | 7082 | 180 | NO |
| C56 | C603H36 | SC220P50V3JN-GP | 78.22134.1BL | C603H36 | 534 | 2528 | 270 | NO |
| C57 | C603H36 | SC220P50V3JN-GP | 78.22134.1BL | C603H36 | 627 | 2570 | 0 | NO |
| C58 | C402H22 | SCD1U25V2KX-GP | 78.10422.5FL | C402H22 | 930 | 14428 | 270 | NO |
| C253 | C603H36 | SC4D7U6D3V3KX-GP | 78.47520.5BL | C603H36 | 1633 | 6993 | 0 | NO |
| C254 | C402H22 | SCD1U16V2KX-3GP | 78.10421.2FL | C402H22 | 1505 | 7010 | 180 | NO |
| C255 | C603H36 | SCD1U25V3KX-LL-GP | 78.10422.2BLLL | C603H36 | 1575 | 14625 | 270 | NO |
| C256 | C402H22 | SCD1U16V2KX-3GP | 78.10421.2FL | C402H22 | 1425 | 6955 | 270 | NO |
| C257 | C603H36 | SC1U25V3KX-1-GP | 78.10522.5BL | C603H36 | 1467 | 4795 | 0 | NO |
| C258 | C603H36 | SC1U25V3KX-1-GP | 78.10522.5BL | C603H36 | 1039 | 4794 | 0 | NO |
| C259 | C1206H71 | SC10U25V6KX-1GP | 78.10622.52L | C1206H71 | 1301.96 | 13923 | 270 | NO |
| C260 | C1206H71 | SC10U25V6KX-1GP | 78.10622.52L | C1206H71 | 1115 | 13875 | 270 | NO |
| C261 | C1206H71 | SC10U25V6KX-1GP | 78.10622.52L | C1206H71 | 1485 | 13875 | 90 | NO |
| CN1 | A2541WR0-1TX5PA-6T-0E | JWT-CON5-42-GP | 21.61427.105 | A2541WR0-1TX5PA-6T-0E | 159.06 | 19003.939999999999 | 270 | NO |
| CN2 | A2541WR0-1TX5PA-6T-0E | JWT-CON5-42-GP | 21.61427.105 | A2541WR0-1TX5PA-6T-0E | 159.06 | 14671.65 | 270 | NO |
| CN3 | A2541WR0-1TX5PA-6T-0E | JWT-CON5-42-GP | 21.61427.105 | A2541WR0-1TX5PA-6T-0E | 159.06 | 12073.23 | 270 | NO |
| CN4 | A2541WR0-1TX5PA-6T-0E | JWT-CON5-42-GP | 21.61427.105 | A2541WR0-1TX5PA-6T-0E | 159.06 | 7611.81 | 270 | NO |
| CN5 | A2541WR0-1TX5PA-6T-0E | JWT-CON5-42-GP | 21.61427.105 | A2541WR0-1TX5PA-6T-0E | 159.06 | 5013.3900000000003 | 270 | NO |
| CN6 | A2541WR0-1TX5PA-6T-0E | JWT-CON5-42-GP | 21.61427.105 | A2541WR0-1TX5PA-6T-0E | 159.06 | 681.1 | 270 | NO |
| CN8 | A2541WV0-1QX3PA-6T | JWT-CON3-S11-GP | 21.61359.103 | A2541WV0-1QX3PA-6T | 1289.3699999999999 | 17788.189999999999 | 0 | NO |
| CN9 | 51952-220LF | FCI-CONN52-4R-1-GP | 20.81943.024 | 51952-220LF | 807.09 | 2244.09 | 270 | NO |
| CN10 | 51952-220LF | FCI-CONN52-4R-1-GP | 20.81943.024 | 51952-220LF | 1496.06 | 2244.09 | 270 | NO |
| D1 | SOD123AKH48 | BAS16H-GP | 83.00016.A1H | SOD123AKH48 | 1025 | 685 | 90 | NO |
| D2 | SOD123AKH48 | BAS16H-GP | 83.00016.A1H | SOD123AKH48 | 517 | 5930 | 90 | NO |
| D3 | SOD123AKH48 | BAS16H-GP | 83.00016.A1H | SOD123AKH48 | 846.03 | 545.02 | 90 | NO |
| D4 | SOD123AKH48 | BAS16H-GP | 83.00016.A1H | SOD123AKH48 | 650 | 5840 | 270 | NO |
| D5 | SOD123AKH48 | BAS16H-GP | 83.00016.A1H | SOD123AKH48 | 711 | 10321 | 90 | NO |
| D6 | SOD123AKH48 | BAS16H-GP | 83.00016.A1H | SOD123AKH48 | 880 | 7404 | 90 | NO |
| D7 | SOD123AKH48 | BAS16H-GP | 83.00016.A1H | SOD123AKH48 | 668 | 10118 | 90 | NO |
| D8 | SOD123AKH48 | BAS16H-GP | 83.00016.A1H | SOD123AKH48 | 885 | 7154 | 90 | NO |
| D9 | SOD123AKH48 | BAS16H-GP | 83.00016.A1H | SOD123AKH48 | 702.02 | 11316.97 | 0 | NO |
| D10 | SOD123AKH48 | BAS16H-GP | 83.00016.A1H | SOD123AKH48 | 885.02 | 11295.97 | 0 | NO |
| D11 | SOD123AKH48 | BAS16H-GP | 83.00016.A1H | SOD123AKH48 | 280 | 17810 | 90 | NO |
| D12 | SOD123AKH48 | BAS16H-GP | 83.00016.A1H | SOD123AKH48 | 416 | 17609 | 0 | NO |
| D13 | D5226155AKH91 | BZG05C3V9-GP | 83.3R903.03G | D5226155AKH91 | 1260 | 7105 | 90 | NO |
| D14 | D8059AKH101 | MBRS340T3G-GP | 83.3R004.B8D | D8059AKH101 | 1727 | 15077 | 270 | NO |
| D15 | D8059AKH101 | MBRS340T3G-GP | 83.3R004.B8D | D8059AKH101 | 845 | 3619 | 270 | NO |
| D16 | D8059AKH101 | MBRS340T3G-GP | 83.3R004.B8D | D8059AKH101 | 1256 | 3618 | 90 | NO |
| D18 | SOD80CAKH36 | CH751H-40PT-1GP | 83.R0304.B3F | SOD80CAKH36 | 1586 | 14422.04 | 0 | NO |
| D19 | SOD80CAKH36 | CH751H-40PT-1GP | 83.R0304.B3F | SOD80CAKH36 | 1411 | 14058.96 | 180 | NO |
| F1 | FUSE-7452-UH50 | FUSE-3A15V-GP | 69.50007.821 | FUSE-7452-UH50 | 856 | 862 | 0 | NO |
| F2 | FUSE-7452-UH50 | FUSE-3A15V-GP | 69.50007.821 | FUSE-7452-UH50 | 734.03 | 6201.02 | 90 | NO |
| F3 | FUSE-7452-UH50 | FUSE-3A15V-GP | 69.50007.821 | FUSE-7452-UH50 | 860.02 | 7578.97 | 0 | NO |
| F4 | FUSE-7452-UH50 | FUSE-3A15V-GP | 69.50007.821 | FUSE-7452-UH50 | 771 | 10501 | 0 | NO |
| F5 | FUSE-7452-UH50 | FUSE-3A15V-GP | 69.50007.821 | FUSE-7452-UH50 | 1220.97 | 11386.98 | 270 | NO |
| F6 | FUSE-7452-UH50 | FUSE-3A15V-GP | 69.50007.821 | FUSE-7452-UH50 | 984.97 | 18965.98 | 270 | NO |
| H1 | HOLE315R138 | HOLE315R138 | ZZ.0HOLE.XXX | HOLE315R138 | 1791.34 | 787.4 | 0 | NO |
| H2 | HOLE315R158 | HOLE315R158 | ZZ.0HOLE.XXX | HOLE315R158 | 275.58999999999997 | 1574.8 | 0 | NO |
| H3 | HOLE315R158 | HOLE315R158 | ZZ.0HOLE.XXX | HOLE315R158 | 1791.34 | 18897.64 | 0 | NO |
| H4 | HOLE315R138 | HOLE315R138 | ZZ.0HOLE.XXX | HOLE315R138 | 177.16 | 13385.83 | 0 | NO |
| H5 | HOLE315R138 | HOLE315R138 | ZZ.0HOLE.XXX | HOLE315R138 | 275.58999999999997 | 18110.23 | 0 | NO |
| H6 | HOLE315R138 | HOLE315R138 | ZZ.0HOLE.XXX | HOLE315R138 | 1791.34 | 11614.17 | 0 | NO |
| H7 | HOLE315R138 | HOLE315R138 | ZZ.0HOLE.XXX | HOLE315R138 | 275.58999999999997 | 6299.21 | 0 | NO |
| H8 | HOLE315R138 | HOLE315R138 | ZZ.0HOLE.XXX | HOLE315R138 | 1791.33 | 5708.66 | 0 | NO |
| H9 | STF375R199H50 | STF375R199H50-GP | 34.64W05.001 | STF375R199H50 | 964.57 | 18230.310000000001 | 90 | YES |
| H10 | STF375R199H50 | STF375R199H50-GP | 34.64W05.001 | STF375R199H50 | 964.57 | 17478.349999999999 | 90 | YES |
| H11 | STF375R199H50 | STF375R199H50-GP | 34.64W05.001 | STF375R199H50 | 1614.17 | 18230.310000000001 | 90 | YES |
| H12 | STF375R199H50 | STF375R199H50-GP | 34.64W05.001 | STF375R199H50 | 1614.17 | 17478.349999999999 | 90 | YES |
| H13 | STF375R199H50 | STF375R199H50-GP | 34.64W05.001 | STF375R199H50 | 1789.37 | 13287.4 | 90 | YES |
| JP1 | 21S-H91-03GB31 | PIN-CON3-S3-GP | 21.61942.103 | 21S-H91-03GB31 | 1650 | 13805 | 90 | NO |
| L1 | L1608-UH38 | FCM1608CF-121T03-GP | 68.00217.561 | L1608-UH38 | 1585.35 | 6068.79 | 180 | NO |
| L2 | L1608-UH38 | FCM1608CF-121T03-GP | 68.00217.561 | L1608-UH38 | 1792.21 | 6135.35 | 270 | NO |
| LED1 | LED-100-3P-067106H325 | LED-RB-6-GP | 06.1BETB.14B | LED-100-3P-067106H325 | 312.99 | 17476.38 | 270 | NO |
| LED2 | LED-100-3P-067106H325 | LED-RB-6-GP | 06.1BETB.14B | LED-100-3P-067106H325 | 312.99 | 16199.41 | 270 | NO |
| LED3 | LED-100-3P-067106H325 | LED-RB-6-GP | 06.1BETB.14B | LED-100-3P-067106H325 | 312.99 | 10545.87 | 270 | NO |
| LED4 | LED-100-3P-067106H325 | LED-RB-6-GP | 06.1BETB.14B | LED-100-3P-067106H325 | 312.99 | 9139.17 | 270 | NO |
| LED5 | LED-100-3P-067106H325 | LED-RB-6-GP | 06.1BETB.14B | LED-100-3P-067106H325 | 312.99 | 3485.63 | 270 | NO |
| LED6 | LED-100-3P-067106H325 | LED-RB-6-GP | 06.1BETB.14B | LED-100-3P-067106H325 | 312.99 | 2208.66 | 270 | NO |
| OSC1 | SMD-OSC8H52 | OSC-33MHZ-7-GP | 82.20034.191 | SMD-OSC8H52 | 1655.85 | 6403.29 | 180 | NO |
| PAD1 | PAD-1P-424137-2-OG | PAD-1P-424137-2-OG-GP | ZZ.00PAD.2I1 | PAD-1P-424137-2-OG | 964.57 | 17734.25 | 90 | NO |
| PAD2 | PAD-1P-424137-1-OG | PAD-1P-424137-1-OG-GP | ZZ.00PAD.2H1 | PAD-1P-424137-1-OG | 1614.17 | 17734.25 | 90 | NO |
| PC1 | C603H36 | SC1U25V3KX-1-GP | 78.10522.5BL | C603H36 | 1040 | 14745 | 270 | NO |
| PC2 | C805H56 | SC10U25V5KX-GP | 78.10622.51L | C805H56 | 1029.7 | 14806.4 | 270 | NO |
| PC3 | C402H22 | SCD01U25V2KX-3GP | 78.10322.2FL | C402H22 | 930 | 14349 | 270 | NO |
| PC4 | C603H36 | SC1U25V3KX-1-GP | 78.10522.5BL | C603H36 | 920 | 14555 | 270 | NO |
| PC5 | C402H22 | SCD01U25V2KX-3GP | 78.10322.2FL | C402H22 | 930 | 14315 | 270 | NO |
| PC6 | C603 | SCD022U50V3KX-2-GP | 78.22324.2BL | C603 | 1335 | 14740 | 0 | NO |
| PC7 | C805H58 | SC1U25V5KX-1GP | 78.10522.21L | C805H58 | 1875 | 16065 | 90 | NO |
| PC8 | C805H58 | SC1U25V5KX-1GP | 78.10522.21L | C805H58 | 1845 | 16410 | 90 | NO |
| PC9 | C805H58 | SC1U25V5KX-1GP | 78.10522.21L | C805H58 | 895 | 14655 | 180 | NO |
| PC10 | C805H58 | SC1U25V5KX-1GP | 78.10522.21L | C805H58 | 840 | 14775 | 270 | NO |
| PC40 | C1206H38 | SC4D7U50V6KX-L2-GP | 78.47524.L2L | C1206H38 | 638 | 9811 | 180 | NO |
| PC41 | C402H22 | SCD1U16V2KX-3GP | 78.10421.2FL | C402H22 | 801 | 9662 | 270 | NO |
| PC42 | C603H36 | SC22P50V3JN-DLGP | 78.22034.1BLDL | C603H36 | 1035 | 9770 | 180 | NO |
| PC43 | C1206H71 | SC22U16V6MX-GP | 78.22611.52L | C1206H71 | 960 | 9365 | 0 | NO |
| PC85 | C402H22 | SCD01U25V2KX-3GP | 78.10322.2FL | C402H22 | 1004 | 5533 | 90 | NO |
| PC86 | C402H22 | SCD01U25V2KX-3GP | 78.10322.2FL | C402H22 | 1616 | 5493 | 270 | NO |
| PC87 | C402H22 | SC220P50V2KX-3GP | 78.22124.2FL | C402H22 | 886 | 5378 | 90 | NO |
| PC88 | C402H22 | SC220P50V2KX-3GP | 78.22124.2FL | C402H22 | 1627 | 5365 | 90 | NO |
| PC89 | C402H22 | SCD1U25V2KX-GP | 78.10422.5FL | C402H22 | 979 | 5378 | 90 | NO |
| PC90 | C402H22 | SCD1U25V2KX-GP | 78.10422.5FL | C402H22 | 1724 | 5364 | 90 | NO |
| PC91 | C603H36 | SCD01U50V3KX-4GP | 78.10324.2BL | C603H36 | 741 | 5734 | 180 | NO |
| PC92 | C603H36 | SCD01U50V3KX-4GP | 78.10324.2BL | C603H36 | 1404 | 5696 | 180 | NO |
| PC93 | C402H22 | SC220P50V2KX-3GP | 78.22124.2FL | C402H22 | 874 | 5759 | 180 | NO |
| PC94 | C402H22 | SC220P50V2KX-3GP | 78.22124.2FL | C402H22 | 1495 | 5804 | 180 | NO |
| PC95 | C805H56 | SC10U25V5KX-GP | 78.10622.51L | C805H56 | 1721 | 5453 | 0 | NO |
| PC96 | C603H36 | SCD1U50V3KX-GP | 78.10424.2BL | C603H36 | 963 | 5605 | 0 | NO |
| PC97 | C805H56 | SC10U25V5KX-GP | 78.10622.51L | C805H56 | 1114 | 5583 | 90 | NO |
| PC98 | C603H36 | SCD1U50V3KX-GP | 78.10424.2BL | C603H36 | 1629 | 5533 | 270 | NO |
| PC1262 | C1206H71 | SC10U16V6KX-2GP | 78.10621.22L | C1206H71 | 1470 | 7265 | 180 | NO |
| PD1 | SOD323AKH44 | MM3Z15VT1G-GP | 83.15R03.B3F | SOD323AKH44 | 1423 | 14763 | 180 | NO |
| PD2 | TVS794591-114297H104 | SMCJ15A-1-GP | 83.00015.0AD | TVS794591-114297H104 | 465 | 16805 | 90 | NO |
| PL7 | L6362-D620H119 | IND-22UH-169-GP | 68.2201D.10J | L6362-D620H119 | 753 | 9496 | 90 | NO |
| PQ1 | LFPAK-5PH48-U | PH0925CL-GP | 84.00925.03N | LFPAK-5PH48-U | 1010 | 15755 | 0 | NO |
| PQ2 | LFPAK-5PH48-U | PH0925CL-GP | 84.00925.03N | LFPAK-5PH48-U | 1360 | 15755 | 0 | NO |
| PQ3 | LFPAK-5PH48-U | PH0925CL-GP | 84.00925.03N | LFPAK-5PH48-U | 1700 | 15755 | 0 | NO |
| PQ4 | SOT23CBE2D4H44 | MMBT3906-3-GP | 84.03906.R11 | SOT23CBE2D4H44 | 1475 | 14410 | 180 | NO |
| PQ5 | SOT-23-10H44 | PMBS3904-1-GP | 84.03904.L06 | SOT-23-10H44 | 1425.69 | 14260.19 | 0 | NO |
| PQ6 | SOT-23-10H44 | PMBS3904-1-GP | 84.03904.L06 | SOT-23-10H44 | 1693.69 | 14412.19 | 0 | NO |
| PQ7 | LFPAK-5PH48-U | PH0925CL-GP | 84.00925.03N | LFPAK-5PH48-U | 1040 | 4395 | 0 | NO |
| PQ8 | LFPAK-5PH48-U | PH0925CL-GP | 84.00925.03N | LFPAK-5PH48-U | 1485 | 4395 | 0 | NO |
| PQ9 | SOT-23-10H44 | PMBS3904-1-GP | 84.03904.L06 | SOT-23-10H44 | 1455 | 6860 | 0 | NO |
| PQ10 | SOT-23-10H44 | PMBS3904-1-GP | 84.03904.L06 | SOT-23-10H44 | 1354 | 7263 | 0 | NO |
| PQ11 | LFPAK-5PH48-U | PH0925CL-GP | 84.00925.03N | LFPAK-5PH48-U | 765 | 4400 | 0 | NO |
| PQ12 | LFPAK-5PH48-U | PH0925CL-GP | 84.00925.03N | LFPAK-5PH48-U | 1765 | 4395 | 0 | NO |
| PQ13 | LFPAK-5PH48-U | PH0925CL-GP | 84.00925.03N | LFPAK-5PH48-U | 679 | 15756 | 0 | NO |
| PQ14 | SOT-23-10H44 | PMBS3904-1-GP | 84.03904.L06 | SOT-23-10H44 | 1519 | 14052.04 | 0 | NO |
| PR1 | R402H16 | 100KR2F-L1-GP | 64.10035.6DL | R402H16 | 930 | 14390 | 90 | NO |
| PR2 | R402H14 | 10R2F-L-GP | 64.10R05.6DL | R402H14 | 1075 | 14885 | 0 | NO |
| PR3 | R402H16 | 51K1R2F-GP | 64.51125.6DL | R402H16 | 930 | 14465 | 270 | NO |
| PR4 | R402H16 | 49K9R2F-L-GP | 64.49925.6DL | R402H16 | 1419 | 14533 | 270 | NO |
| PR5 | R402H16 | 0R2J-2-GP | 63.R0034.1DL | R402H16 | 915 | 14220 | 0 | NO |
| PR6 | R402H16 | 100KR2F-L1-GP | 64.10035.6DL | R402H16 | 1422 | 14624 | 270 | NO |
| PR7 | R402H16 | 1KR2F-3-GP | 64.10015.6DL | R402H16 | 1422 | 14664 | 270 | NO |
| PR8 | R402H16 | 11KR2F-L-GP | 64.11025.6DL | R402H16 | 1422 | 14584 | 90 | NO |
| PR9 | R402H16 | 0R2J-2-GP | 63.R0034.1DL | R402H16 | 1005 | 14220 | 0 | NO |
| PR10 | 0R0402-PAD-1 | 0R0402-PAD-2-GP | ZZ.00PAD.M11 | 0R0402-PAD-1 | 1290 | 14755 | 180 | NO |
| PR11 | R402H16 | 150KR2F-L-GP | 64.15035.6DL | R402H16 | 956 | 14220 | 180 | NO |
| PR12 | R402H16 | 0R2J-2-GP | 63.R0034.1DL | R402H16 | 1114 | 14259 | 90 | NO |
| PR14 | R402H16 | 0R2J-2-GP | 63.R0034.1DL | R402H16 | 1305 | 14820 | 90 | NO |
| PR15 | R402H16 | 4K7R2J-2-GP | 63.47234.1DL | R402H16 | 1180 | 14225 | 180 | NO |
| PR16 | R402H16 | 1KR2F-3-GP | 64.10015.6DL | R402H16 | 1114 | 14216 | 270 | NO |
| PR17 | R402H14 | 10R2F-L-GP | 64.10R05.6DL | R402H14 | 1090 | 15000 | 180 | NO |
| PR18 | R402H14 | 10R2F-L-GP | 64.10R05.6DL | R402H14 | 1130 | 15000 | 180 | NO |
| PR19 | R402H14 | 10R2F-L-GP | 64.10R05.6DL | R402H14 | 1170 | 15000 | 180 | NO |
| PR20 | R402H14 | 10R2F-L-GP | 64.10R05.6DL | R402H14 | 1210 | 15000 | 180 | NO |
| PR21 | R402H14 | 10R2F-L-GP | 64.10R05.6DL | R402H14 | 1250 | 15000 | 180 | NO |
| PR22 | R402H14 | 10R2F-L-GP | 64.10R05.6DL | R402H14 | 1290 | 15000 | 180 | NO |
| PR23 | R402H14 | 10R2F-L-GP | 64.10R05.6DL | R402H14 | 1330 | 15000 | 180 | NO |
| PR24 | R402H14 | 10R2F-L-GP | 64.10R05.6DL | R402H14 | 1370 | 15000 | 180 | NO |
| PR25 | R402H16 | 0R2J-2-GP | 63.R0034.1DL | R402H16 | 1485 | 14724 | 180 | NO |
| PR26 | R402H14 | 10R2F-L-GP | 64.10R05.6DL | R402H14 | 1420 | 14895 | 180 | NO |
| PR27 | R402H14 | 10R2F-L-GP | 64.10R05.6DL | R402H14 | 1465 | 14895 | 180 | NO |
| PR28 | R402H14 | 10R2F-L-GP | 64.10R05.6DL | R402H14 | 1510 | 14895 | 180 | NO |
| PR29 | RL3115-4PH45 | D0005RL1632F-GP-U | 64.0U505.L0L | RL3115-4PH45 | 735 | 16165 | 0 | NO |
| PR30 | RL3115-4PH45 | D0005RL1632F-GP-U | 64.0U505.L0L | RL3115-4PH45 | 1040 | 16165 | 0 | NO |
| PR31 | RL3115-4PH45 | D0005RL1632F-GP-U | 64.0U505.L0L | RL3115-4PH45 | 1325 | 16165 | 0 | NO |
| PR32 | RL3115-4PH45 | D0005RL1632F-GP-U | 64.0U505.L0L | RL3115-4PH45 | 1600 | 16165 | 0 | NO |
| PR33 | R402H16 | 51KR2F-L-GP | 64.51025.6DL | R402H16 | 835 | 14635 | 0 | NO |
| PR34 | R402H16 | 51KR2F-L-GP | 64.51025.6DL | R402H16 | 860 | 14840 | 90 | NO |
| PR35 | R402H16 | 4K7R2J-2-GP | 63.47234.1DL | R402H16 | 930 | 14510 | 90 | NO |
| PR36 | R402H16 | 4K02R2F-GP | 64.40215.6DL | R402H16 | 955 | 14625 | 180 | NO |
| PR37 | R402H16 | 4K99R2F-L-GP | 64.49915.6DL | R402H16 | 935 | 14775 | 180 | NO |
| PR38 | R402H16 | 1KR2F-3-GP | 64.10015.6DL | R402H16 | 1375 | 14420 | 0 | NO |
| PR39 | R402H16 | 5K1R2F-2-GP | 64.51015.6DL | R402H16 | 1315 | 14283 | 270 | NO |
| PR40 | R402H16 | 54K9R2F-L-GP | 64.54925.6DL | R402H16 | 1523.31 | 14293.81 | 180 | NO |
| PR41 | R402H16 | 1KR2F-3-GP | 64.10015.6DL | R402H16 | 1608.31 | 14285.81 | 180 | NO |
| PR42 | R402H16 | 10KR2F-2-GP | 64.10025.6DL | R402H16 | 1566.31 | 14293.81 | 180 | NO |
| PR43 | R805H24 | 1K5R5J-GP | 63.15231.16L | R805H24 | 1670 | 14615 | 0 | NO |
| PR44 | R402H16 | 1KR2F-3-GP | 64.10015.6DL | R402H16 | 1545 | 6855 | 0 | NO |
| PR45 | R402H16 | 10KR2F-2-GP | 64.10025.6DL | R402H16 | 1545 | 7010 | 180 | NO |
| PR46 | R402H16 | 51KR2F-L-GP | 64.51025.6DL | R402H16 | 1538 | 14234 | 90 | NO |
| PR47 | R402H16 | 4K7R2J-2-GP | 63.47234.1DL | R402H16 | 1677 | 6979 | 180 | NO |
| PR48 | R402H16 | 5K1R2F-2-GP | 64.51015.6DL | R402H16 | 1590 | 14580 | 270 | NO |
| PR49 | R402H16 | 4K7R2J-2-GP | 63.47234.1DL | R402H16 | 1654 | 14285 | 180 | NO |
| PR51 | R402H14 | 10R2F-L-GP | 64.10R05.6DL | R402H14 | 1379 | 14894 | 180 | NO |
| PR52 | R603H22 | 47KR3F-GP | 64.47025.55L | R603H22 | 708 | 9786 | 180 | NO |
| PR53 | R603H22 | 10KR3J-L1-GP | 63.10333.15L | R603H22 | 738 | 9866 | 270 | NO |
| PR54 | R603H22 | 0R3J-0-U-GP | 63.00000.00L | R603H22 | 940 | 9600 | 180 | NO |
| PR55 | R402H16 | 100KR2F-L1-GP | 64.10035.6DL | R402H16 | 990 | 9780 | 180 | NO |
| PR56 | R603H22 | 22K1R3F-GP | 64.22125.55L | R603H22 | 945 | 9795 | 0 | NO |
| PR57 | 0R0603-PAD-1 | 0R0603-PAD-2-GP | ZZ.00PAD.M21 | 0R0603-PAD-1 | 571 | 9771 | 0 | NO |
| PR58 | R402H16 | 10KR2F-2-GP | 64.10025.6DL | R402H16 | 1537.96 | 14150 | 90 | NO |
| PR59 | R402H16 | 4K7R2F-GP | 64.47015.6DL | R402H16 | 1537.96 | 14192 | 90 | NO |
| PR60 | R2512-2H32 | D002R2512F-GP | 64.R0025.97L | R2512-2H32 | 720 | 4825 | 0 | NO |
| PR61 | R2512-2H32 | D002R2512F-GP | 64.R0025.97L | R2512-2H32 | 900 | 4825 | 0 | NO |
| PR62 | R2512-2H32 | D002R2512F-GP | 64.R0025.97L | R2512-2H32 | 1760 | 4820 | 0 | NO |
| PR63 | R2512-2H32 | D002R2512F-GP | 64.R0025.97L | R2512-2H32 | 1580 | 4820 | 0 | NO |
| PR94 | R402H16 | 0R2J-2-GP | 63.R0034.1DL | R402H16 | 961 | 5322 | 0 | NO |
| PR95 | R402H16 | 0R2J-2-GP | 63.R0034.1DL | R402H16 | 814 | 5322 | 0 | NO |
| PR96 | R402H16 | 0R2J-2-GP | 63.R0034.1DL | R402H16 | 1706 | 5308 | 0 | NO |
| PR97 | R402H16 | 0R2J-2-GP | 63.R0034.1DL | R402H16 | 1556 | 5307 | 0 | NO |
| PR98 | R603H22 | 1MR3J-L-GP | 63.10533.15L | R603H22 | 887.29 | 5336.79 | 270 | NO |
| PR99 | R402H14 | 100R2F-L1-GP-U | 64.10005.6DL | R402H14 | 1004 | 5496 | 270 | NO |
| PR100 | R603H22 | 1MR3J-L-GP | 63.10533.15L | R603H22 | 1631 | 5321 | 270 | NO |
| PR101 | R402H14 | 100R2F-L1-GP-U | 64.10005.6DL | R402H14 | 1616 | 5456 | 90 | NO |
| PR102 | R402H14 | 10R2F-L-GP | 64.10R05.6DL | R402H14 | 1196 | 4375 | 90 | NO |
| PR103 | R402H14 | 10R2F-L-GP | 64.10R05.6DL | R402H14 | 1518 | 4308 | 270 | NO |
| PR104 | R402H16 | 2K7R2F-GP | 64.27015.6DL | R402H16 | 737 | 5416 | 180 | NO |
| PR105 | R402H16 | 2K7R2F-GP | 64.27015.6DL | R402H16 | 1367.79 | 5413.71 | 180 | NO |
| PR106 | R402H16 | 1KR2F-3-GP | 64.10015.6DL | R402H16 | 739 | 5571 | 180 | NO |
| PR107 | R402H16 | 1KR2F-3-GP | 64.10015.6DL | R402H16 | 1366.79 | 5554.71 | 180 | NO |
| PR108 | R402H16 | 6K81R2F-1-GP | 64.68115.6DL | R402H16 | 1545 | 5870 | 270 | NO |
| PR109 | R402H16 | 6K81R2F-1-GP | 64.68115.6DL | R402H16 | 1580 | 5769 | 0 | NO |
| PR110 | R402H16 | 178KR2F-GP | 64.17835.6DL | R402H16 | 854 | 5699 | 270 | NO |
| PR111 | R402H16 | 178KR2F-GP | 64.17835.6DL | R402H16 | 1470 | 5680 | 270 | NO |
| PR112 | R402H16 | 6K81R2F-1-GP | 64.68115.6DL | R402H16 | 913 | 5715 | 180 | NO |
| PR113 | R402H16 | 6K81R2F-1-GP | 64.68115.6DL | R402H16 | 1535 | 5683 | 180 | NO |
| PR114 | R402H16 | 20KR2F-L-GP | 64.20025.6DL | R402H16 | 786 | 5728 | 180 | NO |
| PR115 | R402H16 | 20KR2F-L-GP | 64.20025.6DL | R402H16 | 1453 | 5805 | 180 | NO |
| PR116 | R402H16 | 0R2J-2-GP | 63.R0034.1DL | R402H16 | 1050 | 14220 | 0 | NO |
| PR117 | R603H22 | 3K3R3F-GP | 64.33015.55L | R603H22 | 1249 | 7254 | 0 | NO |
| PR118 | R402H14 | 10R2F-L-GP | 64.10R05.6DL | R402H14 | 725 | 4313 | 90 | NO |
| PR119 | R402H14 | 10R2F-L-GP | 64.10R05.6DL | R402H14 | 1925 | 4395 | 90 | NO |
| PU1 | QFN20-G3D25H32 | ADM1276-3ACPZ-RL-GP | 74.01276.B7Z | QFN20-G3D25H32 | 1170 | 14520 | 90 | NO |
| PU6 | MSOP10H44 | TPS2490DGSR-GP | 74.02490.A79 | MSOP10H44 | 854 | 5529 | 180 | NO |
| PU7 | MSOP10H44 | TPS2490DGSR-GP | 74.02490.A79 | MSOP10H44 | 1492 | 5511 | 180 | NO |
| Q1 | SOT-23-10H44 | PMBS3904-1-GP | 84.03904.L06 | SOT-23-10H44 | 1082.68 | 5708.66 | 90 | NO |
| Q2 | SOT-23-10H44 | PMBS3904-1-GP | 84.03904.L06 | SOT-23-10H44 | 1082.68 | 12598.43 | 90 | NO |
| Q3 | SOT-23-10H44 | PMBS3904-1-GP | 84.03904.L06 | SOT-23-10H44 | 235.96 | 2588.0300000000002 | 180 | NO |
| Q4 | SOT-23-10H44 | PMBS3904-1-GP | 84.03904.L06 | SOT-23-10H44 | 288 | 3091 | 0 | NO |
| Q5 | SOT-23-10H44 | PMBS3904-1-GP | 84.03904.L06 | SOT-23-10H44 | 548.16999999999996 | 9061.18 | 180 | NO |
| Q6 | SOT-23-10H44 | PMBS3904-1-GP | 84.03904.L06 | SOT-23-10H44 | 281.18 | 10930.83 | 90 | NO |
| Q7 | SOT-23-10H44 | PMBS3904-1-GP | 84.03904.L06 | SOT-23-10H44 | 315 | 16453 | 180 | NO |
| Q8 | SOT-23-10H44 | PMBS3904-1-GP | 84.03904.L06 | SOT-23-10H44 | 234.17 | 17111.18 | 180 | NO |
| Q10 | SOT-363H44 | 2N7002DW-7F-GP | 84.27002.C3F | SOT-363H44 | 1101 | 13997 | 90 | NO |
| Q49 | SOT23DGS2D4H44 | 2N7002-11-GP | 84.27002.W31 | SOT23DGS2D4H44 | 1250 | 14057.04 | 0 | NO |
| R1 | R402H16 | 0R2J-2-GP | 63.R0034.1DL | R402H16 | 1442.35 | 6516.29 | 180 | NO |
| R2 | R402H16 | 0R2J-2-GP | 63.R0034.1DL | R402H16 | 1484.35 | 6516.29 | 180 | NO |
| R3 | R402H16 | 4K7R2F-GP | 64.47015.6DL | R402H16 | 1803.65 | 6440.71 | 0 | NO |
| R4 | R402H16 | 0R2J-2-GP | 63.R0034.1DL | R402H16 | 924.65 | 6086.71 | 0 | NO |
| R5 | R402H16 | 0R2J-2-GP | 63.R0034.1DL | R402H16 | 1513.35 | 6341.29 | 180 | NO |
| R6 | R402H16 | 0R2J-2-GP | 63.R0034.1DL | R402H16 | 1540.29 | 6150.65 | 90 | NO |
| R7 | R402H16 | 0R2J-2-GP | 63.R0034.1DL | R402H16 | 1293.3499999999999 | 6603.29 | 180 | NO |
| R8 | R805H24 | 0R5J-5-GP | 63.R0031.16L | R805H24 | 894.35 | 6388.29 | 180 | NO |
| R9 | R402H16 | 100KR2J-1-GP | 63.10434.1DL | R402H16 | 1377.65 | 6603.71 | 0 | NO |
| R10 | R402H16 | 1MR2J-1-GP | 63.10534.1DL | R402H16 | 972.65 | 5957.71 | 0 | NO |
| R11 | R402H16 | 100KR2J-1-GP | 63.10434.1DL | R402H16 | 1335.35 | 6603.29 | 180 | NO |
| R12 | R402H16 | 4K7R2F-GP | 64.47015.6DL | R402H16 | 930.65 | 5957.71 | 0 | NO |
| R14 | R402H16 | 110KR2F-L-GP | 64.11035.L0L | R402H16 | 1760 | 6243 | 270 | NO |
| R15 | R402H16 | 10KR2F-2-GP | 64.10025.6DL | R402H16 | 1644 | 6267 | 270 | NO |
| R16 | R402H16 | 110KR2F-L-GP | 64.11035.L0L | R402H16 | 1168 | 5868.96 | 180 | NO |
| R17 | R402H16 | 100KR2F-L1-GP | 64.10035.6DL | R402H16 | 1275.56 | 6836.65 | 90 | NO |
| R18 | R402H16 | 100KR2F-L1-GP | 64.10035.6DL | R402H16 | 1275.56 | 6880.65 | 90 | NO |
| R19 | R402H16 | 100KR2F-L1-GP | 64.10035.6DL | R402H16 | 1276.56 | 6921.65 | 90 | NO |
| R20 | R402H16 | 4K7R2F-GP | 64.47015.6DL | R402H16 | 952 | 6640 | 0 | NO |
| R21 | R402H16 | 100KR2F-L1-GP | 64.10035.6DL | R402H16 | 930 | 6710 | 270 | NO |
| R22 | R402H16 | 4K7R2F-GP | 64.47015.6DL | R402H16 | 824 | 6864 | 90 | NO |
| R23 | R402H16 | 4K7R2F-GP | 64.47015.6DL | R402H16 | 802.56 | 6904.65 | 90 | NO |
| R24 | R402H16 | 4K7R2F-GP | 64.47015.6DL | R402H16 | 802.44 | 6946.35 | 270 | NO |
| R25 | R402H16 | 33R2F-3-GP | 64.33R05.6DL | R402H16 | 327 | 2552 | 0 | NO |
| R26 | R402H16 | 0R2J-2-GP | 63.R0034.1DL | R402H16 | 372 | 2552 | 180 | NO |
| R27 | R402H16 | 33R2F-3-GP | 64.33R05.6DL | R402H16 | 203 | 16443 | 90 | NO |
| R28 | R402H16 | 0R2J-2-GP | 63.R0034.1DL | R402H16 | 203 | 16402 | 270 | NO |
| R29 | R402H16 | 33R2F-3-GP | 64.33R05.6DL | R402H16 | 308 | 3213 | 90 | NO |
| R30 | R402H16 | 0R2J-2-GP | 63.R0034.1DL | R402H16 | 392 | 3455 | 0 | NO |
| R31 | R402H16 | 33R2F-3-GP | 64.33R05.6DL | R402H16 | 219 | 16928 | 90 | NO |
| R32 | R402H16 | 0R2J-2-GP | 63.R0034.1DL | R402H16 | 259 | 17234 | 0 | NO |
| R33 | R402H16 | 33R2F-3-GP | 64.33R05.6DL | R402H16 | 434 | 8944 | 180 | NO |
| R34 | R402H16 | 0R2J-2-GP | 63.R0034.1DL | R402H16 | 471 | 9164 | 90 | NO |
| R35 | R402H16 | 10KR2F-2-GP | 64.10025.6DL | R402H16 | 1208 | 5869.04 | 0 | NO |
| R36 | R402H16 | 110KR2F-L-GP | 64.11035.L0L | R402H16 | 1289 | 5868.96 | 180 | NO |
| R37 | R402H16 | 33R2F-3-GP | 64.33R05.6DL | R402H16 | 260 | 11060 | 270 | NO |
| R38 | R402H16 | 0R2J-2-GP | 63.R0034.1DL | R402H16 | 318 | 10836 | 90 | NO |
| R39 | R402H16 | 4K7R2J-2-GP | 63.47234.1DL | R402H16 | 1105 | 9380 | 180 | NO |
| R40 | R402H16 | 4K7R2J-2-GP | 63.47234.1DL | R402H16 | 1173 | 9380 | 180 | NO |
| R41 | R402H16 | 4K7R2J-2-GP | 63.47234.1DL | R402H16 | 1216.71 | 9380.56 | 180 | NO |
| R42 | R402H16 | 4K7R2J-2-GP | 63.47234.1DL | R402H16 | 1125.29 | 9540.44 | 0 | NO |
| R43 | R402H16 | 4K7R2J-2-GP | 63.47234.1DL | R402H16 | 1175.29 | 9540.44 | 0 | NO |
| R44 | R402H16 | 4K7R2J-2-GP | 63.47234.1DL | R402H16 | 1225.29 | 9540.44 | 0 | NO |
| R45 | R402H16 | 0R2J-2-GP | 63.R0034.1DL | R402H16 | 1148 | 9996 | 180 | NO |
| R46 | R402H16 | 0R2J-2-GP | 63.R0034.1DL | R402H16 | 1193 | 9996 | 180 | NO |
| R47 | R402H16 | 0R2J-2-GP | 63.R0034.1DL | R402H16 | 1233 | 9996 | 180 | NO |
| R48 | R402H16 | 4K7R2J-2-GP | 63.47234.1DL | R402H16 | 1438 | 10015 | 0 | NO |
| R49 | R402H16 | 4K7R2F-GP | 64.47015.6DL | R402H16 | 574 | 6751 | 0 | NO |
| R50 | R402H16 | 0R2J-2-GP | 63.R0034.1DL | R402H16 | 1644 | 6227 | 90 | NO |
| R51 | R402H16 | 0R2J-2-GP | 63.R0034.1DL | R402H16 | 1702 | 6254 | 0 | NO |
| R52 | R402H16 | 4K7R2F-GP | 64.47015.6DL | R402H16 | 614 | 6751 | 0 | NO |
| R54 | R402H16 | 4K7R2J-2-GP | 63.47234.1DL | R402H16 | 1315 | 9461 | 180 | NO |
| R55 | R402H16 | 4K7R2J-2-GP | 63.47234.1DL | R402H16 | 1360 | 9461 | 180 | NO |
| R56 | R402H16 | 4K7R2J-2-GP | 63.47234.1DL | R402H16 | 1405 | 9461 | 180 | NO |
| R58 | R402H16 | 330R2J-3-GP | 63.33134.1DL | R402H16 | 1521 | 10015 | 0 | NO |
| R59 | R402H16 | 330R2J-3-GP | 63.33134.1DL | R402H16 | 1479 | 10014 | 0 | NO |
| R60 | R402H16 | 4K7R2F-GP | 64.47015.6DL | R402H16 | 630 | 2660 | 0 | NO |
| R61 | R402H16 | 4K7R2F-GP | 64.47015.6DL | R402H16 | 626 | 2475 | 180 | NO |
| R62 | R402H16 | 0R2J-2-GP | 63.R0034.1DL | R402H16 | 482 | 2134 | 90 | NO |
| R63 | R402H16 | 0R2J-2-GP | 63.R0034.1DL | R402H16 | 482 | 2174 | 270 | NO |
| R64 | R402H16 | 4K7R2F-GP | 64.47015.6DL | R402H16 | 317 | 5708 | 270 | NO |
| R65 | R402H16 | 4K7R2F-GP | 64.47015.6DL | R402H16 | 690 | 635 | 270 | NO |
| R66 | R402H16 | 4K7R2F-GP | 64.47015.6DL | R402H16 | 390 | 5796 | 180 | NO |
| R67 | R402H16 | 4K7R2F-GP | 64.47015.6DL | R402H16 | 673.98 | 693.03 | 180 | NO |
| R68 | R402H16 | 4K7R2F-GP | 64.47015.6DL | R402H16 | 627 | 5772 | 90 | NO |
| R69 | R402H16 | 4K7R2F-GP | 64.47015.6DL | R402H16 | 679.98 | 548.03 | 180 | NO |
| R70 | R603H22 | 27KR3F-GP | 64.27025.55L | R603H22 | 451 | 5801 | 0 | NO |
| R71 | R603H22 | 27KR3F-GP | 64.27025.55L | R603H22 | 785 | 715 | 90 | NO |
| R72 | R603H22 | 27KR3F-GP | 64.27025.55L | R603H22 | 707 | 5910 | 270 | NO |
| R73 | R603H22 | 27KR3F-GP | 64.27025.55L | R603H22 | 810.47 | 613.98 | 270 | NO |
| R74 | R402H16 | 10KR2F-2-GP | 64.10025.6DL | R402H16 | 496 | 5752 | 0 | NO |
| R75 | R402H16 | 10KR2F-2-GP | 64.10025.6DL | R402H16 | 875 | 715 | 90 | NO |
| R76 | R402H16 | 10KR2F-2-GP | 64.10025.6DL | R402H16 | 784 | 5893 | 0 | NO |
| R77 | R402H16 | 10KR2F-2-GP | 64.10025.6DL | R402H16 | 900.03 | 615.02 | 90 | NO |
| R78 | R402H16 | 4K7R2F-GP | 64.47015.6DL | R402H16 | 741 | 10209 | 270 | NO |
| R79 | R402H16 | 4K7R2F-GP | 64.47015.6DL | R402H16 | 670 | 7300 | 270 | NO |
| R80 | R402H16 | 4K7R2F-GP | 64.47015.6DL | R402H16 | 740 | 10254 | 270 | NO |
| R81 | R402H16 | 4K7R2F-GP | 64.47015.6DL | R402H16 | 880 | 7334 | 270 | NO |
| R82 | R402H16 | 4K7R2F-GP | 64.47015.6DL | R402H16 | 704 | 10043 | 270 | NO |
| R83 | R402H16 | 4K7R2F-GP | 64.47015.6DL | R402H16 | 895 | 7079 | 270 | NO |
| R84 | R603H22 | 27KR3F-GP | 64.27025.55L | R603H22 | 648 | 10250 | 270 | NO |
| R85 | R603H22 | 27KR3F-GP | 64.27025.55L | R603H22 | 815 | 7304 | 0 | NO |
| R86 | R603H22 | 27KR3F-GP | 64.27025.55L | R603H22 | 642 | 10013 | 180 | NO |
| R87 | R603H22 | 27KR3F-GP | 64.27025.55L | R603H22 | 820 | 7054 | 180 | NO |
| R88 | R402H16 | 10KR2F-2-GP | 64.10025.6DL | R402H16 | 613 | 10206 | 270 | NO |
| R89 | R402H16 | 10KR2F-2-GP | 64.10025.6DL | R402H16 | 770 | 7291 | 180 | NO |
| R90 | R402H16 | 10KR2F-2-GP | 64.10025.6DL | R402H16 | 704 | 9998 | 90 | NO |
| R91 | R402H16 | 10KR2F-2-GP | 64.10025.6DL | R402H16 | 772 | 7042 | 180 | NO |
| R92 | R402H16 | 4K7R2F-GP | 64.47015.6DL | R402H16 | 705 | 11751 | 270 | NO |
| R93 | R402H16 | 4K7R2F-GP | 64.47015.6DL | R402H16 | 634.98 | 11221.03 | 180 | NO |
| R94 | R402H16 | 4K7R2F-GP | 64.47015.6DL | R402H16 | 813.98 | 11244.03 | 180 | NO |
| R95 | R402H16 | 4K7R2F-GP | 64.47015.6DL | R402H16 | 324 | 17744 | 270 | NO |
| R96 | R402H16 | 4K7R2F-GP | 64.47015.6DL | R402H16 | 367 | 17882 | 270 | NO |
| R97 | R402H16 | 4K7R2F-GP | 64.47015.6DL | R402H16 | 483 | 17540 | 180 | NO |
| R98 | R603H22 | 27KR3F-GP | 64.27025.55L | R603H22 | 632.02 | 11311.47 | 0 | NO |
| R99 | R603H22 | 27KR3F-GP | 64.27025.55L | R603H22 | 813.98 | 11349.53 | 180 | NO |
| R100 | R603H22 | 27KR3F-GP | 64.27025.55L | R603H22 | 308 | 17699 | 90 | NO |
| R101 | R603H22 | 27KR3F-GP | 64.27025.55L | R603H22 | 515 | 17647 | 90 | NO |
| R102 | R402H16 | 10KR2F-2-GP | 64.10025.6DL | R402H16 | 631.98 | 11403.03 | 180 | NO |
| R103 | R402H16 | 10KR2F-2-GP | 64.10025.6DL | R402H16 | 770.02 | 11361.97 | 0 | NO |
| R104 | R402H16 | 10KR2F-2-GP | 64.10025.6DL | R402H16 | 216 | 17696 | 270 | NO |
| R105 | R402H16 | 10KR2F-2-GP | 64.10025.6DL | R402H16 | 511 | 17698 | 90 | NO |
| R106 | R402H16 | 0R2J-2-GP | 63.R0034.1DL | R402H16 | 1350 | 10015 | 180 | NO |
| R107 | R402H16 | 0R2J-2-GP | 63.R0034.1DL | R402H16 | 1391 | 10014 | 180 | NO |
| R108 | R402H16 | 0R2J-2-GP | 63.R0034.1DL | R402H16 | 1275 | 14225 | 180 | NO |
| R109 | R402H16 | 0R2J-2-GP | 63.R0034.1DL | R402H16 | 1230 | 14225 | 180 | NO |
| R111 | R402H16 | 2KR2F-3-GP | 64.20015.6DL | R402H16 | 343.82 | 2642.17 | 270 | NO |
| R113 | R402H16 | 2KR2F-3-GP | 64.20015.6DL | R402H16 | 192.83 | 3089.82 | 0 | NO |
| R114 | R402H16 | 470R2F-GP | 64.47005.6DL | R402H16 | 586 | 1793 | 90 | NO |
| R115 | R402H16 | 2KR2F-3-GP | 64.20015.6DL | R402H16 | 641 | 9111 | 0 | NO |
| R116 | R402H16 | 470R2F-GP | 64.47005.6DL | R402H16 | 586 | 1633 | 90 | NO |
| R117 | R402H16 | 2KR2F-3-GP | 64.20015.6DL | R402H16 | 397 | 10960 | 270 | NO |
| R118 | R402H16 | 470R2F-GP | 64.47005.6DL | R402H16 | 586 | 1713 | 270 | NO |
| R119 | R402H16 | 2KR2F-3-GP | 64.20015.6DL | R402H16 | 329 | 16625 | 0 | NO |
| R120 | R402H16 | 470R2F-GP | 64.47005.6DL | R402H16 | 586 | 1553 | 90 | NO |
| R121 | R402H16 | 2KR2F-3-GP | 64.20015.6DL | R402H16 | 201 | 17207 | 90 | NO |
| R122 | R1206H28 | 1K8R6J-GP | 63.18232.11L | R1206H28 | 334 | 2469 | 270 | NO |
| R123 | R1206H28 | 1K8R6J-GP | 63.18232.11L | R1206H28 | 308 | 3285 | 90 | NO |
| R124 | R1206H28 | 1K8R6J-GP | 63.18232.11L | R1206H28 | 499 | 8893 | 180 | NO |
| R125 | R1206H28 | 1K8R6J-GP | 63.18232.11L | R1206H28 | 390 | 10280 | 180 | NO |
| R126 | R1206H28 | 1K8R6J-GP | 63.18232.11L | R1206H28 | 217 | 16571 | 90 | NO |
| R127 | R1206H28 | 1K8R6J-GP | 63.18232.11L | R1206H28 | 213 | 16992 | 90 | NO |
| R128 | R402H16 | 10KR2F-2-GP | 64.10025.6DL | R402H16 | 1249 | 5869.04 | 0 | NO |
| R129 | R402H16 | 330R2J-3-GP | 63.33134.1DL | R402H16 | 1595 | 9960 | 0 | NO |
| R130 | R402H16 | 4K7R2F-GP | 64.47015.6DL | R402H16 | 856.96 | 8441 | 90 | NO |
| R131 | R402H16 | 4K7R2F-GP | 64.47015.6DL | R402H16 | 856.96 | 8485 | 90 | NO |
| R132 | R402H16 | 4K7R2F-GP | 64.47015.6DL | R402H16 | 856.96 | 8529 | 90 | NO |
| R133 | R402H16 | 4K7R2F-GP | 64.47015.6DL | R402H16 | 857 | 8572 | 90 | NO |
| R134 | R402H16 | 4K7R2F-GP | 64.47015.6DL | R402H16 | 857 | 8615 | 90 | NO |
| R135 | R402H16 | 4K7R2F-GP | 64.47015.6DL | R402H16 | 857 | 8657 | 90 | NO |
| R136 | R402H16 | 0R2J-2-GP | 63.R0034.1DL | R402H16 | 1029 | 8300.9599999999991 | 180 | NO |
| R137 | R402H16 | 0R2J-2-GP | 63.R0034.1DL | R402H16 | 1112 | 8301 | 180 | NO |
| R138 | R402H16 | 0R2J-2-GP | 63.R0034.1DL | R402H16 | 1193 | 8831 | 0 | NO |
| R139 | R402H16 | 0R2J-2-GP | 63.R0034.1DL | R402H16 | 1196 | 8301 | 180 | NO |
| R140 | R402H16 | 0R2J-2-GP | 63.R0034.1DL | R402H16 | 1109 | 8831 | 0 | NO |
| R141 | R402H16 | 0R2J-2-GP | 63.R0034.1DL | R402H16 | 1026 | 8831 | 0 | NO |
| R148 | R402H16 | 330R2J-3-GP | 63.33134.1DL | R402H16 | 1450 | 9475 | 180 | NO |
| R149 | R402H16 | 330R2J-3-GP | 63.33134.1DL | R402H16 | 1635 | 9960 | 0 | NO |
| R150 | R402H14 | 10R2F-L-GP | 64.10R05.6DL | R402H14 | 583 | 2616 | 180 | NO |
| R151 | R402H14 | 10R2F-L-GP | 64.10R05.6DL | R402H14 | 543 | 2616 | 180 | NO |
| R154 | 0R0805-PAD-1 | 0R0805-PAD-2-GP | ZZ.00PAD.M31 | 0R0805-PAD-1 | 1045 | 9365 | 0 | NO |
| R155 | R402H16 | 330R2J-3-GP | 63.33134.1DL | R402H16 | 1570 | 9475 | 180 | NO |
| R156 | R402H16 | 330R2J-3-GP | 63.33134.1DL | R402H16 | 1530 | 9475 | 180 | NO |
| R157 | R402H16 | 330R2J-3-GP | 63.33134.1DL | R402H16 | 1490 | 9475 | 180 | NO |
| R161 | R402H16 | 0R2J-2-GP | 63.R0034.1DL | R402H16 | 1163 | 6689 | 180 | NO |
| R162 | R402H16 | 0R2J-2-GP | 63.R0034.1DL | R402H16 | 1156 | 6585 | 180 | NO |
| R163 | R402H16 | 0R2J-2-GP | 63.R0034.1DL | R402H16 | 1049 | 6605 | 180 | NO |
| R164 | R402H16 | 0R2J-2-GP | 63.R0034.1DL | R402H16 | 1066 | 6622 | 270 | NO |
| R165 | R402H16 | 0R2J-2-GP | 63.R0034.1DL | R402H16 | 1173 | 6602 | 270 | NO |
| R166 | R402H16 | 4K7R2F-GP | 64.47015.6DL | R402H16 | 345 | 2723 | 90 | NO |
| R167 | R402H16 | 4K7R2F-GP | 64.47015.6DL | R402H16 | 586 | 2800 | 270 | NO |
| R171 | R402H16 | 0R2J-2-GP | 63.R0034.1DL | R402H16 | 586 | 1753 | 90 | NO |
| R172 | R402H16 | 0R2J-2-GP | 63.R0034.1DL | R402H16 | 586 | 1593 | 90 | NO |
| R173 | R402H16 | 0R2J-2-GP | 63.R0034.1DL | R402H16 | 586 | 1673 | 270 | NO |
| R174 | R402H16 | 0R2J-2-GP | 63.R0034.1DL | R402H16 | 586 | 1833 | 270 | NO |
| R175 | R402H16 | 0R2J-2-GP | 63.R0034.1DL | R402H16 | 586 | 1993 | 90 | NO |
| R176 | R402H16 | 0R2J-2-GP | 63.R0034.1DL | R402H16 | 1146 | 6706 | 90 | NO |
| R177 | 0R1206-PAD-1 | 0R1206-PAD-1-GP | ZZ.R1206.ZZ1 | 0R1206-PAD-1 | 801 | 18959 | 0 | NO |
| R178 | 0R1206-PAD-1 | 0R1206-PAD-1-GP | ZZ.R1206.ZZ1 | 0R1206-PAD-1 | 1051 | 11395 | 0 | NO |
| R179 | 0R1206-PAD-1 | 0R1206-PAD-1-GP | ZZ.R1206.ZZ1 | 0R1206-PAD-1 | 720 | 10697 | 90 | NO |
| R180 | 0R1206-PAD-1 | 0R1206-PAD-1-GP | ZZ.R1206.ZZ1 | 0R1206-PAD-1 | 862 | 7767 | 90 | NO |
| R181 | 0R1206-PAD-1 | 0R1206-PAD-1-GP | ZZ.R1206.ZZ1 | 0R1206-PAD-1 | 560 | 6195 | 180 | NO |
| R182 | 0R1206-PAD-1 | 0R1206-PAD-1-GP | ZZ.R1206.ZZ1 | 0R1206-PAD-1 | 816 | 1030 | 90 | NO |
| R183 | R402H16 | 0R2J-2-GP | 63.R0034.1DL | R402H16 | 817 | 6822 | 270 | NO |
| R184 | R402H16 | 0R2J-2-GP | 63.R0034.1DL | R402H16 | 606 | 1933 | 180 | NO |
| R185 | R402H16 | 0R2J-2-GP | 63.R0034.1DL | R402H16 | 586 | 1873 | 270 | NO |
| R186 | R402H16 | 0R2J-2-GP | 63.R0034.1DL | R402H16 | 566 | 1933 | 0 | NO |
| R260 | R402H16 | 47KR2J-2-GP | 63.47334.1DL | R402H16 | 1585 | 7010 | 180 | NO |
| R261 | R402H16 | 10KR2J-3-GP | 63.10334.1DL | R402H16 | 1495 | 7100 | 0 | NO |
| R270 | R402H16 | 0R2J-2-GP | 63.R0034.1DL | R402H16 | 1735 | 7011 | 90 | NO |
| R357 | R402H16 | 10KR2F-2-GP | 64.10025.6DL | R402H16 | 616 | 2096 | 180 | NO |
| R358 | R402H16 | 10KR2F-2-GP | 64.10025.6DL | R402H16 | 595 | 2170 | 90 | NO |
| R359 | R402H16 | 10KR2F-2-GP | 64.10025.6DL | R402H16 | 610 | 2383 | 180 | NO |
| R360 | R402H14 | 100R2J-2-GP | 63.10134.1DL | R402H14 | 574 | 2096 | 0 | NO |
| R361 | R402H14 | 100R2J-2-GP | 63.10134.1DL | R402H14 | 595 | 2210 | 270 | NO |
| R362 | R402H14 | 100R2J-2-GP | 63.10134.1DL | R402H14 | 569 | 2383 | 0 | NO |
| R363 | R402H16 | 5K1R2F-2-GP | 64.51015.6DL | R402H16 | 1497.04 | 13940 | 270 | NO |
| R364 | R402H16 | 0R2J-2-GP | 63.R0034.1DL | R402H16 | 1350 | 14101.04 | 0 | NO |
| R365 | R402H16 | 10MR2J-L-GP | 63.10634.1DL | R402H16 | 1347 | 14023.04 | 0 | NO |
| R366 | R402H16 | 10KR2F-2-GP | 64.10025.6DL | R402H16 | 1136 | 14082 | 90 | NO |
| R367 | R402H16 | 10KR2F-2-GP | 64.10025.6DL | R402H16 | 1058 | 14081 | 270 | NO |
| TC1 | CT7343H79 | ST68U16VDM-1-GP | 77.26861.05L | CT7343H79 | 353 | 3978 | 270 | NO |
| TC2 | CT7343H79 | ST68U16VDM-1-GP | 77.26861.05L | CT7343H79 | 353 | 4183 | 270 | NO |
| TC3 | CT7343H79 | ST68U16VDM-1-GP | 77.26861.05L | CT7343H79 | 935 | 4190 | 90 | NO |
| TC4 | CT7343H79 | ST15U25VDM-1-GP | 77.21561.00L | CT7343H79 | 935 | 3985 | 90 | NO |
| TC5 | CT7343H79 | ST68U16VDM-1-GP | 77.26861.05L | CT7343H79 | 1730 | 3769 | 90 | NO |
| TC6 | CT7343H79 | ST68U16VDM-1-GP | 77.26861.05L | CT7343H79 | 1728 | 3567 | 90 | NO |
| TC7 | CT7343H79 | ST68U16VDM-1-GP | 77.26861.05L | CT7343H79 | 1729 | 4184 | 90 | NO |
| TC8 | CT7343H79 | ST15U25VDM-1-GP | 77.21561.00L | CT7343H79 | 1729 | 3979 | 90 | NO |
| TC9 | CT7343H79 | ST68U16VDM-1-GP | 77.26861.05L | CT7343H79 | 1725 | 15315 | 90 | NO |
| TC10 | CT7343H79 | ST68U16VDM-1-GP | 77.26861.05L | CT7343H79 | 1726 | 15516 | 90 | NO |
| TC11 | CT7343H79 | ST68U16VDM-1-GP | 77.26861.05L | CT7343H79 | 789 | 15111 | 0 | NO |
| TC12 | CT7343H79 | ST15U25VDM-1-GP | 77.21561.00L | CT7343H79 | 490 | 15515 | 270 | NO |
| TC13 | CT7343H79 | ST15U25VDM-1-GP | 77.21561.00L | CT7343H79 | 1255 | 885 | 90 | NO |
| TC14 | CT7343H79 | ST15U25VDM-1-GP | 77.21561.00L | CT7343H79 | 315 | 6670 | 270 | NO |
| TC15 | CT7343H79 | ST15U25VDM-1-GP | 77.21561.00L | CT7343H79 | 860 | 7984 | 270 | NO |
| TC16 | CT7343H79 | ST15U25VDM-1-GP | 77.21561.00L | CT7343H79 | 761 | 10906 | 270 | NO |
| TC17 | CT7343H79 | ST15U25VDM-1-GP | 77.21561.00L | CT7343H79 | 1457.98 | 11389.03 | 180 | NO |
| TC18 | CT7343H79 | ST15U25VDM-1-GP | 77.21561.00L | CT7343H79 | 1242.98 | 18959.03 | 180 | NO |
| TP1 | TPAD32 | TPAD32-GP | ZZ.0TPAD.191 | TPAD32 | 1050 | 6032 | 180 | NO |
| TP5 | TPAD32 | TPAD32-GP | ZZ.0TPAD.191 | TPAD32 | 1019 | 6541 | 180 | NO |
| TP6 | TPAD32 | TPAD32-GP | ZZ.0TPAD.191 | TPAD32 | 1258.3499999999999 | 5936.29 | 180 | NO |
| TP9 | TPAD32 | TPAD32-GP | ZZ.0TPAD.191 | TPAD32 | 1327.35 | 5934.29 | 180 | NO |
| TP10 | TPAD32 | TPAD32-GP | ZZ.0TPAD.191 | TPAD32 | 1319.35 | 6019.29 | 180 | NO |
| TP11 | TPAD32 | TPAD32-GP | ZZ.0TPAD.191 | TPAD32 | 1401.35 | 5932.29 | 180 | NO |
| TP12 | TPAD32 | TPAD32-GP | ZZ.0TPAD.191 | TPAD32 | 1567 | 6268 | 90 | NO |
| TP13 | TPAD32 | TPAD32-GP | ZZ.0TPAD.191 | TPAD32 | 1399.29 | 6041.65 | 90 | NO |
| TP14 | TPAD32 | TPAD32-GP | ZZ.0TPAD.191 | TPAD32 | 1443.29 | 5987.65 | 90 | NO |
| TP15 | TPAD32 | TPAD32-GP | ZZ.0TPAD.191 | TPAD32 | 1510.29 | 6275.65 | 90 | NO |
| TP16 | TPAD32 | TPAD32-GP | ZZ.0TPAD.191 | TPAD32 | 929.71 | 6173.35 | 270 | NO |
| TP17 | TPAD32 | TPAD32-GP | ZZ.0TPAD.191 | TPAD32 | 1607 | 6159 | 180 | NO |
| TP18 | TPAD32 | TPAD32-GP | ZZ.0TPAD.191 | TPAD32 | 1420 | 9945 | 270 | NO |
| TP19 | TPAD32 | TPAD32-GP | ZZ.0TPAD.191 | TPAD32 | 1540 | 9945 | 270 | NO |
| TP21 | TPAD32 | TPAD32-GP | ZZ.0TPAD.191 | TPAD32 | 1790 | 7065 | 0 | NO |
| TP22 | TPAD32 | TPAD32-GP | ZZ.0TPAD.191 | TPAD32 | 1171 | 14301 | 270 | NO |
| TP23 | TPAD32 | TPAD32-GP | ZZ.0TPAD.191 | TPAD32 | 739 | 5501 | 90 | NO |
| TP24 | TPAD32 | TPAD32-GP | ZZ.0TPAD.191 | TPAD32 | 1367.71 | 5485.21 | 90 | NO |
| TP26 | TPAD32 | TPAD32-GP | ZZ.0TPAD.191 | TPAD32 | 1476 | 9946 | 0 | NO |
| U1 | LQFP48H63 | NCT7904D-GP | 71.07904.A0G | LQFP48H63 | 1195.3499999999999 | 6293.29 | 180 | NO |
| U2 | SOIC8-G3627H69 | NCT7368S-GP | 74.07368.071 | SOIC8-G3627H69 | 1032.56 | 6849.15 | 90 | NO |
| U3 | SC70-5H44 | 74LVC1G32GW-1GP | 73.01G32.AHH | SC70-5H44 | 694.35 | 6778.56 | 180 | NO |
| U4 | SOT-6H56 | SY8201ABC-GP | 74.08201.04P | SOT-6H56 | 827 | 9763 | 90 | NO |
| U5 | SSOIC8-1H44 | 24LC64T-I-GP | 72.02464.00Q | SSOIC8-1H44 | 1178 | 9741 | 0 | NO |
| U6 | TSOIC16H44 | PCA9551PW-T-2GP-U | 71.09551.A0W | TSOIC16H44 | 1463 | 9706 | 0 | NO |
| U7 | TSOIC14H48 | TSLV07APWR-GP | 73.07407.BHB | TSOIC14H48 | 1085 | 8574.0400000000009 | 0 | NO |
| U8 | TSOIC14H48 | TSAHC74PWR-GP | 73.07474.BAB | TSOIC14H48 | 1635 | 7212.04 | 0 | NO |
| U10 | SC70-5H44 | 74LVC1G32GW-1GP | 73.01G32.AHH | SC70-5H44 | 395 | 6880 | 90 | NO |
| U11 | SC70-5H44 | 74LVC1G32GW-1GP | 73.01G32.AHH | SC70-5H44 | 550 | 6880 | 90 | NO |
